(kicad_pcb
	(version 20260206)
	(generator "pcbnew")
	(generator_version "10.0")
	(general
		(thickness 1.6)
		(legacy_teardrops no)
	)
	(paper "A4")
	(title_block
		(title "pdpb — Lightning_PDPB_BRD.brd")
		(comment 1 "Lightning (Wiwynn / Facebook NVMe JBOF) / footprints 122-122 of 1140")
	)
	(layers
		(0 "F.Cu" signal "TOP")
		(4 "In1.Cu" signal "L2GND")
		(6 "In2.Cu" signal "L3")
		(8 "In3.Cu" signal "L4VCC")
		(10 "In4.Cu" signal "L5VCC")
		(12 "In5.Cu" signal "L6")
		(14 "In6.Cu" signal "L7GND")
		(2 "B.Cu" signal "BOTTOM")
		(9 "F.Adhes" user "F.Adhesive")
		(11 "B.Adhes" user "B.Adhesive")
		(13 "F.Paste" user "Package Geometry/Pastemask Top")
		(15 "B.Paste" user "Package Geometry/Pastemask Bottom")
		(5 "F.SilkS" user "Ref Des/Silkscreen Top")
		(7 "B.SilkS" user "Ref Des/Silkscreen Bottom")
		(1 "F.Mask" user "Board Geometry/Soldermask Top")
		(3 "B.Mask" user "Board Geometry/Soldermask Bottom")
		(17 "Dwgs.User" user "User.Drawings")
		(19 "Cmts.User" user "User.Comments")
		(21 "Eco1.User" user "User.Eco1")
		(23 "Eco2.User" user "User.Eco2")
		(25 "Edge.Cuts" user "Board Geometry/Outline")
		(27 "Margin" user)
		(31 "F.CrtYd" user "Package Geometry/Place Bound Top")
		(29 "B.CrtYd" user "Package Geometry/Place Bound Bottom")
		(35 "F.Fab" user "Ref Des/Assembly Top")
		(33 "B.Fab" user "Ref Des/Assembly Bottom")
	)
	(footprint ""
		(layer "F.Cu")
		(at 20.850098 -26.329894 -90)
		(property "Reference" "J14"
			(at 0 0 270)
			(layer "F.SilkS")
			(hide yes)
			(effects
				(font
					(size 1.27 1.27)
				)
			)
		)
		(property "Value" "PCISLT68-14-GP-U1"
			(at -22.225 12.7508 270)
			(unlocked yes)
			(layer "F.Fab")
			(hide yes)
			(effects
				(font
					(size 1.016 1.016)
					(thickness 0.1524)
				)
			)
		)
		(property "Device Type" "SD-78827-0001"
			(at -22.225 11.2268 270)
			(unlocked yes)
			(layer "F.Fab")
			(hide yes)
			(effects
				(font
					(size 1.016 1.016)
					(thickness 0.1524)
				)
			)
		)
		(duplicate_pad_numbers_are_jumpers no)
		(fp_line
			(start -20.4724 12.0142)
			(end -20.4724 4.6736)
			(stroke
				(width 0.1524)
				(type default)
			)
			(layer "F.SilkS")
		)
		(fp_line
			(start -17.8435 12.0142)
			(end -20.4724 12.0142)
			(stroke
				(width 0.1524)
				(type default)
			)
			(layer "F.SilkS")
		)
		(fp_line
			(start 17.8435 12.0142)
			(end 17.8435 10.3124)
			(stroke
				(width 0.1524)
				(type default)
			)
			(layer "F.SilkS")
		)
		(fp_line
			(start 20.4724 12.0142)
			(end 17.8435 12.0142)
			(stroke
				(width 0.1524)
				(type default)
			)
			(layer "F.SilkS")
		)
		(fp_line
			(start -17.8435 10.3124)
			(end -17.8435 12.0142)
			(stroke
				(width 0.1524)
				(type default)
			)
			(layer "F.SilkS")
		)
		(fp_line
			(start 17.8435 10.3124)
			(end -17.8435 10.3124)
			(stroke
				(width 0.1524)
				(type default)
			)
			(layer "F.SilkS")
		)
		(fp_line
			(start -23.749 4.6736)
			(end -23.749 0.0254)
			(stroke
				(width 0.1524)
				(type default)
			)
			(layer "F.SilkS")
		)
		(fp_line
			(start -20.4724 4.6736)
			(end -23.749 4.6736)
			(stroke
				(width 0.1524)
				(type default)
			)
			(layer "F.SilkS")
		)
		(fp_line
			(start 20.4724 4.6736)
			(end 20.4724 12.0142)
			(stroke
				(width 0.1524)
				(type default)
			)
			(layer "F.SilkS")
		)
		(fp_line
			(start 23.749 4.6736)
			(end 20.4724 4.6736)
			(stroke
				(width 0.1524)
				(type default)
			)
			(layer "F.SilkS")
		)
		(fp_line
			(start -23.117556 2.896108)
			(end -23.117556 1.803908)
			(stroke
				(width 0.3048)
				(type default)
			)
			(layer "F.SilkS")
		)
		(fp_line
			(start 20.882356 2.896108)
			(end 20.882356 1.803908)
			(stroke
				(width 0.3048)
				(type default)
			)
			(layer "F.SilkS")
		)
		(fp_line
			(start -20.882356 1.803908)
			(end -20.882356 2.896108)
			(stroke
				(width 0.3048)
				(type default)
			)
			(layer "F.SilkS")
		)
		(fp_line
			(start 23.117556 1.803908)
			(end 23.117556 2.896108)
			(stroke
				(width 0.3048)
				(type default)
			)
			(layer "F.SilkS")
		)
		(fp_line
			(start -23.749 0.0254)
			(end -20.4724 0.0254)
			(stroke
				(width 0.1524)
				(type default)
			)
			(layer "F.SilkS")
		)
		(fp_line
			(start -20.4724 0.0254)
			(end -20.4724 -3.4036)
			(stroke
				(width 0.1524)
				(type default)
			)
			(layer "F.SilkS")
		)
		(fp_line
			(start 20.4724 0.0254)
			(end 23.749 0.0254)
			(stroke
				(width 0.1524)
				(type default)
			)
			(layer "F.SilkS")
		)
		(fp_line
			(start 23.749 0.0254)
			(end 23.749 4.6736)
			(stroke
				(width 0.1524)
				(type default)
			)
			(layer "F.SilkS")
		)
		(fp_line
			(start -20.4724 -3.4036)
			(end 20.4724 -3.4036)
			(stroke
				(width 0.1524)
				(type default)
			)
			(layer "F.SilkS")
		)
		(fp_line
			(start 20.4724 -3.4036)
			(end 20.4724 0.0254)
			(stroke
				(width 0.1524)
				(type default)
			)
			(layer "F.SilkS")
		)
		(fp_arc
			(start -20.882356 2.896108)
			(mid -21.999956 4.013708)
			(end -23.117556 2.896108)
			(stroke
				(width 0.3048)
				(type default)
			)
			(layer "F.SilkS")
		)
		(fp_arc
			(start 23.117556 2.896108)
			(mid 21.999956 4.013708)
			(end 20.882356 2.896108)
			(stroke
				(width 0.3048)
				(type default)
			)
			(layer "F.SilkS")
		)
		(fp_arc
			(start -23.117556 1.803908)
			(mid -21.999956 0.686308)
			(end -20.882356 1.803908)
			(stroke
				(width 0.3048)
				(type default)
			)
			(layer "F.SilkS")
		)
		(fp_arc
			(start 20.882356 1.803908)
			(mid 21.999956 0.686308)
			(end 23.117556 1.803908)
			(stroke
				(width 0.3048)
				(type default)
			)
			(layer "F.SilkS")
		)
		(fp_poly
			(pts
				(xy -20.2184 11.7602) (xy -20.2184 4.4196) (xy -23.495 4.4196) (xy -23.495 0.2794) (xy -20.2184 0.2794)
				(xy -20.2184 -3.1496) (xy 20.2184 -3.1496) (xy 20.2184 0.2794) (xy 23.495 0.2794) (xy 23.495 4.4196)
				(xy 20.2184 4.4196) (xy 20.2184 11.7602) (xy 18.0975 11.7602) (xy 18.0975 10.0584) (xy -18.0975 10.0584)
				(xy -18.0975 11.7602)
			)
			(stroke
				(width 0)
				(type default)
			)
			(fill no)
			(layer "F.CrtYd")
		)
		(fp_poly
			(pts
				(xy -21.2471 16.256) (xy -21.2471 4.9276) (xy -24.003 4.9276) (xy -24.003 -0.2286) (xy -20.7264 -0.2286)
				(xy -20.7264 -3.6576) (xy 20.7264 -3.6576) (xy 20.7264 -0.2286) (xy 24.003 -0.2286) (xy 24.003 -0.00635)
				(xy 20.2184 -0.00635) (xy 20.2184 -3.1496) (xy -20.2184 -3.1496) (xy -20.2184 0.2794) (xy -23.495 0.2794)
				(xy -23.495 4.4196) (xy -20.2184 4.4196) (xy -20.2184 11.7602) (xy -18.0975 11.7602) (xy -18.0975 10.0584)
				(xy 18.0975 10.0584) (xy 18.0975 11.7602) (xy 20.2184 11.7602) (xy 20.2184 4.4196) (xy 23.495 4.4196)
				(xy 23.495 0.2794) (xy 20.2184 0.2794) (xy 20.2184 0.00635) (xy 24.003 0.00635) (xy 24.003 4.9276)
				(xy 21.2471 4.9276) (xy 21.2471 16.256)
			)
			(stroke
				(width 0)
				(type default)
			)
			(fill no)
			(layer "F.CrtYd")
		)
		(fp_poly
			(pts
				(xy -21.2471 16.256) (xy -21.2471 4.9276) (xy -24.003 4.9276) (xy -24.003 -0.2286) (xy -20.7264 -0.2286)
				(xy -20.7264 -3.6576) (xy 20.7264 -3.6576) (xy 20.7264 -0.2286) (xy 24.003 -0.2286) (xy 24.003 4.9276)
				(xy 21.2471 4.9276) (xy 21.2471 16.256)
			)
			(stroke
				(width 0)
				(type default)
			)
			(fill no)
			(layer "F.Fab")
		)
		(pad "" np_thru_hole circle
			(at -18.999962 0 270)
			(size 0.254 0.254)
			(drill 1.8542)
			(layers "*.Cu" "*.Mask")
			(clearance 1.1557)
			(thermal_gap 1.1557)
		)
		(pad "" np_thru_hole circle
			(at 18.999962 0 270)
			(size 0.254 0.254)
			(drill 1.8542)
			(layers "*.Cu" "*.Mask")
			(clearance 1.1557)
			(thermal_gap 1.1557)
		)
		(pad "E1" smd rect
			(at -7.079996 1.240028 270)
			(size 0.508 2.0066)
			(layers "F.Cu" "F.Mask" "F.Paste")
			(net "PE_CLK100M_DR14_2_P")
		)
		(pad "E2" smd rect
			(at -6.279896 1.240028 270)
			(size 0.508 2.0066)
			(layers "F.Cu" "F.Mask" "F.Paste")
			(net "PE_CLK100M_DR14_2_N")
		)
		(pad "E3" smd rect
			(at -5.48005 1.240028 270)
			(size 0.508 2.0066)
			(layers "F.Cu" "F.Mask" "F.Paste")
			(net "P3V3")
		)
		(pad "E4" smd rect
			(at -4.67995 1.240028 270)
			(size 0.508 2.0066)
			(layers "F.Cu" "F.Mask" "F.Paste")
			(net "SSD14_PERST_N")
		)
		(pad "E5" smd rect
			(at -3.880104 1.240028 270)
			(size 0.508 2.0066)
			(layers "F.Cu" "F.Mask" "F.Paste")
			(net "SSD14_PERST_N")
		)
		(pad "E6" smd rect
			(at -3.080004 1.240028 270)
			(size 0.508 2.0066)
			(layers "F.Cu" "F.Mask" "F.Paste")
			(net "Net_1215")
		)
		(pad "E7" smd rect
			(at -15.48003 -1.949958 270)
			(size 0.508 2.0066)
			(layers "F.Cu" "F.Mask" "F.Paste")
			(net "PE_CLK100M_DR14_1_P")
		)
		(pad "E8" smd rect
			(at -14.67993 -1.949958 270)
			(size 0.508 2.0066)
			(layers "F.Cu" "F.Mask" "F.Paste")
			(net "PE_CLK100M_DR14_1_N")
		)
		(pad "E9" smd rect
			(at -13.880084 -1.949958 270)
			(size 0.508 2.0066)
			(layers "F.Cu" "F.Mask" "F.Paste")
			(net "GND")
		)
		(pad "E10" smd rect
			(at -13.079984 -1.949958 270)
			(size 0.508 2.0066)
			(layers "F.Cu" "F.Mask" "F.Paste")
			(net "PE_TX1_DR14_N")
		)
		(pad "E11" smd rect
			(at -12.279884 -1.949958 270)
			(size 0.508 2.0066)
			(layers "F.Cu" "F.Mask" "F.Paste")
			(net "PE_TX1_DR14_P")
		)
		(pad "E12" smd rect
			(at -11.480038 -1.949958 270)
			(size 0.508 2.0066)
			(layers "F.Cu" "F.Mask" "F.Paste")
			(net "GND")
		)
		(pad "E13" smd rect
			(at -10.679938 -1.949958 270)
			(size 0.508 2.0066)
			(layers "F.Cu" "F.Mask" "F.Paste")
			(net "PE_RX1_DR14_N")
		)
		(pad "E14" smd rect
			(at -9.880092 -1.949958 270)
			(size 0.508 2.0066)
			(layers "F.Cu" "F.Mask" "F.Paste")
			(net "PE_RX1_DR14_P")
		)
		(pad "E15" smd rect
			(at -9.079992 -1.949958 270)
			(size 0.508 2.0066)
			(layers "F.Cu" "F.Mask" "F.Paste")
			(net "GND")
		)
		(pad "E16" smd rect
			(at -8.279892 -1.949958 270)
			(size 0.508 2.0066)
			(layers "F.Cu" "F.Mask" "F.Paste")
			(net "Net_1222")
		)
		(pad "E17" smd rect
			(at 9.320022 -1.949958 270)
			(size 0.508 2.0066)
			(layers "F.Cu" "F.Mask" "F.Paste")
			(net "PE_TX4_DR14_N")
		)
		(pad "E18" smd rect
			(at 10.120122 -1.949958 270)
			(size 0.508 2.0066)
			(layers "F.Cu" "F.Mask" "F.Paste")
			(net "PE_TX4_DR14_P")
		)
		(pad "E19" smd rect
			(at 10.919968 -1.949958 270)
			(size 0.508 2.0066)
			(layers "F.Cu" "F.Mask" "F.Paste")
			(net "GND")
		)
		(pad "E20" smd rect
			(at 11.720068 -1.949958 270)
			(size 0.508 2.0066)
			(layers "F.Cu" "F.Mask" "F.Paste")
			(net "PE_RX4_DR14_N")
		)
		(pad "E21" smd rect
			(at 12.519914 -1.949958 270)
			(size 0.508 2.0066)
			(layers "F.Cu" "F.Mask" "F.Paste")
			(net "PE_RX4_DR14_P")
		)
		(pad "E22" smd rect
			(at 13.320014 -1.949958 270)
			(size 0.508 2.0066)
			(layers "F.Cu" "F.Mask" "F.Paste")
			(net "GND")
		)
		(pad "E23" smd rect
			(at 14.120114 -1.949958 270)
			(size 0.508 2.0066)
			(layers "F.Cu" "F.Mask" "F.Paste")
			(net "SCL_DR14_R")
		)
		(pad "E24" smd rect
			(at 14.91996 -1.949958 270)
			(size 0.508 2.0066)
			(layers "F.Cu" "F.Mask" "F.Paste")
			(net "SDA_DR14_R")
		)
		(pad "E25" smd rect
			(at 15.72006 -1.949958 270)
			(size 0.508 2.0066)
			(layers "F.Cu" "F.Mask" "F.Paste")
			(net "DUALPORTEN#14")
		)
		(pad "P1" smd rect
			(at -1.905 0.824992 270)
			(size 0.6604 2.0574)
			(layers "F.Cu" "F.Mask" "F.Paste")
			(net "Net_1218")
		)
		(pad "P2" smd rect
			(at -0.635 0.824992 270)
			(size 0.6604 2.0574)
			(layers "F.Cu" "F.Mask" "F.Paste")
			(net "Net_1217")
		)
		(pad "P3" smd rect
			(at 0.635 0.824992 270)
			(size 0.6604 2.0574)
			(layers "F.Cu" "F.Mask" "F.Paste")
			(net "Net_1216")
		)
		(pad "P4" smd rect
			(at 1.905 0.824992 270)
			(size 0.6604 2.0574)
			(layers "F.Cu" "F.Mask" "F.Paste")
			(net "SSD14_CLK0_OE_N")
		)
		(pad "P5" smd rect
			(at 3.175 0.824992 270)
			(size 0.6604 2.0574)
			(layers "F.Cu" "F.Mask" "F.Paste")
			(net "GND")
		)
		(pad "P6" smd rect
			(at 4.445 0.824992 270)
			(size 0.6604 2.0574)
			(layers "F.Cu" "F.Mask" "F.Paste")
			(net "GND")
		)
		(pad "P7" smd rect
			(at 5.715 0.824992 270)
			(size 0.6604 2.0574)
			(layers "F.Cu" "F.Mask" "F.Paste")
			(net "Net_89")
		)
		(pad "P8" smd rect
			(at 6.985 0.824992 270)
			(size 0.6604 2.0574)
			(layers "F.Cu" "F.Mask" "F.Paste")
			(net "Net_61")
		)
		(pad "P9" smd rect
			(at 8.255 0.824992 270)
			(size 0.6604 2.0574)
			(layers "F.Cu" "F.Mask" "F.Paste")
			(net "Net_75")
		)
		(pad "P10" smd rect
			(at 9.525 0.824992 270)
			(size 0.6604 2.0574)
			(layers "F.Cu" "F.Mask" "F.Paste")
			(net "SSD_PRSNT_NET14")
		)
		(pad "P11" smd rect
			(at 10.795 0.824992 270)
			(size 0.6604 2.0574)
			(layers "F.Cu" "F.Mask" "F.Paste")
			(net "SSD_ACT_DR14")
		)
		(pad "P12" smd rect
			(at 12.065 0.824992 270)
			(size 0.6604 2.0574)
			(layers "F.Cu" "F.Mask" "F.Paste")
			(net "GND")
		)
		(pad "P13" smd rect
			(at 13.335 0.824992 270)
			(size 0.6604 2.0574)
			(layers "F.Cu" "F.Mask" "F.Paste")
			(net "12V_PRECH_SSD14")
		)
		(pad "P14" smd rect
			(at 14.605 0.824992 270)
			(size 0.6604 2.0574)
			(layers "F.Cu" "F.Mask" "F.Paste")
			(net "P12V_SSD14")
		)
		(pad "P15" smd rect
			(at 15.875 0.824992 270)
			(size 0.6604 2.0574)
			(layers "F.Cu" "F.Mask" "F.Paste")
			(net "P12V_SSD14")
		)
		(pad "PTH1" thru_hole oval
			(at -21.999956 2.350008 270)
			(size 1.524 2.6162)
			(drill oval 0.8128 1.905)
			(layers "*.Cu" "*.Mask")
			(remove_unused_layers no)
			(net "Net_1227")
			(clearance 0.1524)
			(thermal_gap 0.1524)
		)
		(pad "PTH2" thru_hole oval
			(at 21.999956 2.350008 270)
			(size 1.524 2.6162)
			(drill oval 0.8128 1.905)
			(layers "*.Cu" "*.Mask")
			(remove_unused_layers no)
			(net "Net_1211")
			(clearance 0.1524)
			(thermal_gap 0.1524)
		)
		(pad "S1" smd rect
			(at -15.875 0.824992 270)
			(size 0.6604 2.0574)
			(layers "F.Cu" "F.Mask" "F.Paste")
			(net "GND")
		)
		(pad "S2" smd rect
			(at -14.605 0.824992 270)
			(size 0.6604 2.0574)
			(layers "F.Cu" "F.Mask" "F.Paste")
			(net "Net_1226")
		)
		(pad "S3" smd rect
			(at -13.335 0.824992 270)
			(size 0.6604 2.0574)
			(layers "F.Cu" "F.Mask" "F.Paste")
			(net "Net_1225")
		)
		(pad "S4" smd rect
			(at -12.065 0.824992 270)
			(size 0.6604 2.0574)
			(layers "F.Cu" "F.Mask" "F.Paste")
			(net "GND")
		)
		(pad "S5" smd rect
			(at -10.795 0.824992 270)
			(size 0.6604 2.0574)
			(layers "F.Cu" "F.Mask" "F.Paste")
			(net "Net_1224")
		)
		(pad "S6" smd rect
			(at -9.525 0.824992 270)
			(size 0.6604 2.0574)
			(layers "F.Cu" "F.Mask" "F.Paste")
			(net "Net_1223")
		)
		(pad "S7" smd rect
			(at -8.255 0.824992 270)
			(size 0.6604 2.0574)
			(layers "F.Cu" "F.Mask" "F.Paste")
			(net "GND")
		)
		(pad "S8" smd rect
			(at -7.480046 -1.949958 270)
			(size 0.508 2.0066)
			(layers "F.Cu" "F.Mask" "F.Paste")
			(net "GND")
		)
		(pad "S9" smd rect
			(at -6.679946 -1.949958 270)
			(size 0.508 2.0066)
			(layers "F.Cu" "F.Mask" "F.Paste")
			(net "Net_1221")
		)
		(pad "S10" smd rect
			(at -5.8801 -1.949958 270)
			(size 0.508 2.0066)
			(layers "F.Cu" "F.Mask" "F.Paste")
			(net "Net_1220")
		)
		(pad "S11" smd rect
			(at -5.08 -1.949958 270)
			(size 0.508 2.0066)
			(layers "F.Cu" "F.Mask" "F.Paste")
			(net "GND")
		)
		(pad "S12" smd rect
			(at -4.2799 -1.949958 270)
			(size 0.508 2.0066)
			(layers "F.Cu" "F.Mask" "F.Paste")
			(net "Net_1219")
		)
		(pad "S13" smd rect
			(at -3.480054 -1.949958 270)
			(size 0.508 2.0066)
			(layers "F.Cu" "F.Mask" "F.Paste")
			(net "Net_1214")
		)
		(pad "S14" smd rect
			(at -2.679954 -1.949958 270)
			(size 0.508 2.0066)
			(layers "F.Cu" "F.Mask" "F.Paste")
			(net "GND")
		)
		(pad "S15" smd rect
			(at -1.880108 -1.949958 270)
			(size 0.508 2.0066)
			(layers "F.Cu" "F.Mask" "F.Paste")
			(net "Net_1213")
		)
		(pad "S16" smd rect
			(at -1.080008 -1.949958 270)
			(size 0.508 2.0066)
			(layers "F.Cu" "F.Mask" "F.Paste")
			(net "GND")
		)
		(pad "S17" smd rect
			(at -0.279908 -1.949958 270)
			(size 0.508 2.0066)
			(layers "F.Cu" "F.Mask" "F.Paste")
			(net "PE_TX2_DR14_N")
		)
		(pad "S18" smd rect
			(at 0.519938 -1.949958 270)
			(size 0.508 2.0066)
			(layers "F.Cu" "F.Mask" "F.Paste")
			(net "PE_TX2_DR14_P")
		)
		(pad "S19" smd rect
			(at 1.320038 -1.949958 270)
			(size 0.508 2.0066)
			(layers "F.Cu" "F.Mask" "F.Paste")
			(net "GND")
		)
		(pad "S20" smd rect
			(at 2.119884 -1.949958 270)
			(size 0.508 2.0066)
			(layers "F.Cu" "F.Mask" "F.Paste")
			(net "PE_RX2_DR14_N")
		)
		(pad "S21" smd rect
			(at 2.919984 -1.949958 270)
			(size 0.508 2.0066)
			(layers "F.Cu" "F.Mask" "F.Paste")
			(net "PE_RX2_DR14_P")
		)
		(pad "S22" smd rect
			(at 3.720084 -1.949958 270)
			(size 0.508 2.0066)
			(layers "F.Cu" "F.Mask" "F.Paste")
			(net "GND")
		)
		(pad "S23" smd rect
			(at 4.51993 -1.949958 270)
			(size 0.508 2.0066)
			(layers "F.Cu" "F.Mask" "F.Paste")
			(net "PE_TX3_DR14_N")
		)
		(pad "S24" smd rect
			(at 5.32003 -1.949958 270)
			(size 0.508 2.0066)
			(layers "F.Cu" "F.Mask" "F.Paste")
			(net "PE_TX3_DR14_P")
		)
		(pad "S25" smd rect
			(at 6.119876 -1.949958 270)
			(size 0.508 2.0066)
			(layers "F.Cu" "F.Mask" "F.Paste")
			(net "GND")
		)
		(pad "S26" smd rect
			(at 6.919976 -1.949958 270)
			(size 0.508 2.0066)
			(layers "F.Cu" "F.Mask" "F.Paste")
			(net "PE_RX3_DR14_N")
		)
		(pad "S27" smd rect
			(at 7.720076 -1.949958 270)
			(size 0.508 2.0066)
			(layers "F.Cu" "F.Mask" "F.Paste")
			(net "PE_RX3_DR14_P")
		)
		(pad "S28" smd rect
			(at 8.519922 -1.949958 270)
			(size 0.508 2.0066)
			(layers "F.Cu" "F.Mask" "F.Paste")
			(net "GND")
		)
		(zone
			(layers "F.Cu" "B.Cu" "In1.Cu" "In2.Cu" "In3.Cu" "In4.Cu" "In5.Cu" "In6.Cu")
			(hatch none 0.5)
			(connect_pads
				(clearance 0)
			)
			(min_thickness 0.25)
			(keepout
				(tracks not_allowed)
				(vias allowed)
				(pads allowed)
				(copperpour not_allowed)
				(footprints allowed)
			)
			(placement
				(enabled no)
				(sheetname "")
			)
			(fill
				(thermal_gap 0.5)
				(thermal_bridge_width 0.5)
				(island_removal_mode 0)
			)
			(polygon
				(pts
					(arc
						(start 22.081998 -45.329856)
						(mid 19.618198 -45.329856)
						(end 22.081998 -45.329856)
					)
				)
			)
		)
		(zone
			(layers "F.Cu" "B.Cu" "In1.Cu" "In2.Cu" "In3.Cu" "In4.Cu" "In5.Cu" "In6.Cu")
			(hatch none 0.5)
			(connect_pads
				(clearance 0)
			)
			(min_thickness 0.25)
			(keepout
				(tracks not_allowed)
				(vias allowed)
				(pads allowed)
				(copperpour not_allowed)
				(footprints allowed)
			)
			(placement
				(enabled no)
				(sheetname "")
			)
			(fill
				(thermal_gap 0.5)
				(thermal_bridge_width 0.5)
				(island_removal_mode 0)
			)
			(polygon
				(pts
					(arc
						(start 22.081998 -7.329932)
						(mid 19.618198 -7.329932)
						(end 22.081998 -7.329932)
					)
				)
			)
		)
	)
)
